# S9S_MB_2U (Grand Teton) — schematic netlist excerpt (pin names and nets, part order shuffled) for the footprints in the layout excerpt that follows; sources: Cadence DE-HDL packaged netlist, KiCad conversion of 03242023_DA0F0TMBIJ0_F0T_Motherboard_J_brd_V01_OCP.brd

R4752  Q_RES  0 5% CHIP  pkg 0402LF  page 156 : A = HP_LVC3_OCP_V3_1_PRSNT2_N_R ; B = HP_LVC3_OCP_V3_1_PRSNT2_PLD_N
R3593  Q_RES  33.2 1% CHIP  pkg 0402LF  page 232 : A = SMB_INA230_3V3AUX_SDA ; B = SMB_INA230_5_3V3AUX_SDA_R

(kicad_pcb
	(version 20260206)
	(generator "pcbnew")
	(generator_version "10.0")
	(general
		(thickness 1.6)
		(legacy_teardrops no)
	)
	(paper "A4")
	(title_block
		(title "03242023_DA0F0TMBIJ0_F0T_Motherboard_J_brd_V01_OCP.brd")
		(comment 1 "Grand Teton / footprints 666-667 of 6105")
	)
	(layers
		(0 "F.Cu" signal "TOP")
		(4 "In1.Cu" signal "GND")
		(6 "In2.Cu" signal "IN1")
		(8 "In3.Cu" signal "GND1")
		(10 "In4.Cu" signal "IN2")
		(12 "In5.Cu" signal "GND2")
		(14 "In6.Cu" signal "IN3")
		(16 "In7.Cu" signal "GND3")
		(18 "In8.Cu" signal "VCC")
		(20 "In9.Cu" signal "VCC1")
		(22 "In10.Cu" signal "GND4")
		(24 "In11.Cu" signal "IN4")
		(26 "In12.Cu" signal "GND5")
		(28 "In13.Cu" signal "IN5")
		(30 "In14.Cu" signal "GND6")
		(32 "In15.Cu" signal "IN6")
		(34 "In16.Cu" signal "GND7")
		(2 "B.Cu" signal "BOTTOM")
		(9 "F.Adhes" user "F.Adhesive")
		(11 "B.Adhes" user "B.Adhesive")
		(13 "F.Paste" user "Package Geometry/Pastemask Top")
		(15 "B.Paste" user "Package Geometry/Pastemask Bottom")
		(5 "F.SilkS" user "Ref Des/Silkscreen Top")
		(7 "B.SilkS" user "Ref Des/Silkscreen Bottom")
		(1 "F.Mask" user "Board Geometry/Soldermask Top")
		(3 "B.Mask" user "Board Geometry/Soldermask Bottom")
		(17 "Dwgs.User" user "User.Drawings")
		(19 "Cmts.User" user "User.Comments")
		(21 "Eco1.User" user "User.Eco1")
		(23 "Eco2.User" user "User.Eco2")
		(25 "Edge.Cuts" user "Board Geometry/Outline")
		(27 "Margin" user)
		(31 "F.CrtYd" user "Package Geometry/Place Bound Top")
		(29 "B.CrtYd" user "Package Geometry/Place Bound Bottom")
		(35 "F.Fab" user "Ref Des/Assembly Top")
		(33 "B.Fab" user "Ref Des/Assembly Bottom")
	)
	(footprint ""
		(layer "F.Cu")
		(at 461.593946 -106.027728 180)
		(property "Reference" "R4752"
			(at 0 0 180)
			(layer "F.SilkS")
			(hide yes)
			(effects
				(font
					(size 1.27 1.27)
				)
			)
		)
		(property "Value" ""
			(at 0 0 180)
			(layer "F.Fab")
			(effects
				(font
					(size 1.27 1.27)
				)
			)
		)
		(duplicate_pad_numbers_are_jumpers no)
		(fp_line
			(start 0.7874 0.4064)
			(end -0.7874 0.4064)
			(stroke
				(width 0.1524)
				(type default)
			)
			(layer "F.SilkS")
		)
		(fp_line
			(start 0.7874 -0.4064)
			(end 0.7874 0.4064)
			(stroke
				(width 0.1524)
				(type default)
			)
			(layer "F.SilkS")
		)
		(fp_line
			(start -0.7874 0.4064)
			(end -0.7874 -0.4064)
			(stroke
				(width 0.1524)
				(type default)
			)
			(layer "F.SilkS")
		)
		(fp_line
			(start -0.7874 -0.4064)
			(end 0.7874 -0.4064)
			(stroke
				(width 0.1524)
				(type default)
			)
			(layer "F.SilkS")
		)
		(fp_line
			(start 0.67945 0.3048)
			(end 0.120396 0.3048)
			(stroke
				(width 0.1)
				(type default)
			)
			(layer "F.Fab")
		)
		(fp_line
			(start 0.67945 -0.3048)
			(end 0.67945 0.3048)
			(stroke
				(width 0.1)
				(type default)
			)
			(layer "F.Fab")
		)
		(fp_line
			(start 0.12065 -0.2794)
			(end 0.12065 -0.3048)
			(stroke
				(width 0.1)
				(type default)
			)
			(layer "F.Fab")
		)
		(fp_line
			(start 0.12065 -0.3048)
			(end 0.67945 -0.3048)
			(stroke
				(width 0.1)
				(type default)
			)
			(layer "F.Fab")
		)
		(fp_line
			(start 0.120396 0.3048)
			(end 0.120396 0.2794)
			(stroke
				(width 0.1)
				(type default)
			)
			(layer "F.Fab")
		)
		(fp_line
			(start 0.120396 0.2794)
			(end -0.12065 0.2794)
			(stroke
				(width 0.1)
				(type default)
			)
			(layer "F.Fab")
		)
		(fp_line
			(start -0.12065 0.3048)
			(end -0.67945 0.3048)
			(stroke
				(width 0.1)
				(type default)
			)
			(layer "F.Fab")
		)
		(fp_line
			(start -0.12065 0.2794)
			(end -0.12065 0.3048)
			(stroke
				(width 0.1)
				(type default)
			)
			(layer "F.Fab")
		)
		(fp_line
			(start -0.12065 -0.2794)
			(end 0.12065 -0.2794)
			(stroke
				(width 0.1)
				(type default)
			)
			(layer "F.Fab")
		)
		(fp_line
			(start -0.12065 -0.305054)
			(end -0.12065 -0.2794)
			(stroke
				(width 0.1)
				(type default)
			)
			(layer "F.Fab")
		)
		(fp_line
			(start -0.67945 0.3048)
			(end -0.67945 -0.305054)
			(stroke
				(width 0.1)
				(type default)
			)
			(layer "F.Fab")
		)
		(fp_line
			(start -0.67945 -0.305054)
			(end -0.12065 -0.305054)
			(stroke
				(width 0.1)
				(type default)
			)
			(layer "F.Fab")
		)
		(pad "1" smd circle
			(at -0.40005 0 180)
			(size 0 0)
			(layers "F.Cu" "F.Mask" "F.Paste")
			(net "HP_LVC3_OCP_V3_1_PRSNT2_N_R")
		)
		(pad "2" smd circle
			(at 0.40005 0 180)
			(size 0 0)
			(layers "F.Cu" "F.Mask" "F.Paste")
			(net "HP_LVC3_OCP_V3_1_PRSNT2_PLD_N")
		)
	)
	(footprint ""
		(layer "F.Cu")
		(at 215.95588 -32.857948 180)
		(property "Reference" "R3593"
			(at 0 0 180)
			(layer "F.SilkS")
			(hide yes)
			(effects
				(font
					(size 1.27 1.27)
				)
			)
		)
		(property "Value" ""
			(at 0 0 180)
			(layer "F.Fab")
			(effects
				(font
					(size 1.27 1.27)
				)
			)
		)
		(duplicate_pad_numbers_are_jumpers no)
		(fp_line
			(start 0.7874 0.4064)
			(end -0.7874 0.4064)
			(stroke
				(width 0.1524)
				(type default)
			)
			(layer "F.SilkS")
		)
		(fp_line
			(start 0.7874 -0.4064)
			(end 0.7874 0.4064)
			(stroke
				(width 0.1524)
				(type default)
			)
			(layer "F.SilkS")
		)
		(fp_line
			(start -0.7874 0.4064)
			(end -0.7874 -0.4064)
			(stroke
				(width 0.1524)
				(type default)
			)
			(layer "F.SilkS")
		)
		(fp_line
			(start -0.7874 -0.4064)
			(end 0.7874 -0.4064)
			(stroke
				(width 0.1524)
				(type default)
			)
			(layer "F.SilkS")
		)
		(fp_line
			(start 0.67945 0.3048)
			(end 0.120396 0.3048)
			(stroke
				(width 0.1)
				(type default)
			)
			(layer "F.Fab")
		)
		(fp_line
			(start 0.67945 -0.3048)
			(end 0.67945 0.3048)
			(stroke
				(width 0.1)
				(type default)
			)
			(layer "F.Fab")
		)
		(fp_line
			(start 0.12065 -0.2794)
			(end 0.12065 -0.3048)
			(stroke
				(width 0.1)
				(type default)
			)
			(layer "F.Fab")
		)
		(fp_line
			(start 0.12065 -0.3048)
			(end 0.67945 -0.3048)
			(stroke
				(width 0.1)
				(type default)
			)
			(layer "F.Fab")
		)
		(fp_line
			(start 0.120396 0.3048)
			(end 0.120396 0.2794)
			(stroke
				(width 0.1)
				(type default)
			)
			(layer "F.Fab")
		)
		(fp_line
			(start 0.120396 0.2794)
			(end -0.12065 0.2794)
			(stroke
				(width 0.1)
				(type default)
			)
			(layer "F.Fab")
		)
		(fp_line
			(start -0.12065 0.3048)
			(end -0.67945 0.3048)
			(stroke
				(width 0.1)
				(type default)
			)
			(layer "F.Fab")
		)
		(fp_line
			(start -0.12065 0.2794)
			(end -0.12065 0.3048)
			(stroke
				(width 0.1)
				(type default)
			)
			(layer "F.Fab")
		)
		(fp_line
			(start -0.12065 -0.2794)
			(end 0.12065 -0.2794)
			(stroke
				(width 0.1)
				(type default)
			)
			(layer "F.Fab")
		)
		(fp_line
			(start -0.12065 -0.305054)
			(end -0.12065 -0.2794)
			(stroke
				(width 0.1)
				(type default)
			)
			(layer "F.Fab")
		)
		(fp_line
			(start -0.67945 0.3048)
			(end -0.67945 -0.305054)
			(stroke
				(width 0.1)
				(type default)
			)
			(layer "F.Fab")
		)
		(fp_line
			(start -0.67945 -0.305054)
			(end -0.12065 -0.305054)
			(stroke
				(width 0.1)
				(type default)
			)
			(layer "F.Fab")
		)
		(pad "1" smd circle
			(at -0.40005 0 180)
			(size 0 0)
			(layers "F.Cu" "F.Mask" "F.Paste")
			(net "SMB_INA230_3V3AUX_SDA")
		)
		(pad "2" smd circle
			(at 0.40005 0 180)
			(size 0 0)
			(layers "F.Cu" "F.Mask" "F.Paste")
			(net "SMB_INA230_5_3V3AUX_SDA_R")
		)
	)
)
